# T6G (Grand Teton) — schematic netlist excerpt (pin names and nets, part order shuffled) for the footprints in the layout excerpt that follows; sources: Cadence DE-HDL packaged netlist, KiCad conversion of 04192023_DAF0TMB3IC0_F0TG_MB_C_brd_V02_OCP.brd

C6030  Q_CAP  22UF 6.3V 20% X6S  pkg C0603  page 177 : A = P1V2_CPU0_USB_DVDD12 ; B = GND
R221  Q_RES  33 5% CHIP  pkg 0402LF  page 82 : A = FM_CPU0_SA1 ; B = CPU0_SA1

(kicad_pcb
	(version 20260206)
	(generator "pcbnew")
	(generator_version "10.0")
	(general
		(thickness 1.6)
		(legacy_teardrops no)
	)
	(paper "A4")
	(title_block
		(title "04192023_DAF0TMB3IC0_F0TG_MB_C_brd_V02_OCP.brd")
		(comment 1 "Grand Teton / footprints 5002-5003 of 8354")
	)
	(layers
		(0 "F.Cu" signal "TOP")
		(4 "In1.Cu" signal "GND")
		(6 "In2.Cu" signal "IN1")
		(8 "In3.Cu" signal "GND1")
		(10 "In4.Cu" signal "IN2")
		(12 "In5.Cu" signal "GND2")
		(14 "In6.Cu" signal "IN3")
		(16 "In7.Cu" signal "GND3")
		(18 "In8.Cu" signal "VCC")
		(20 "In9.Cu" signal "VCC1")
		(22 "In10.Cu" signal "GND4")
		(24 "In11.Cu" signal "IN4")
		(26 "In12.Cu" signal "GND5")
		(28 "In13.Cu" signal "IN5")
		(30 "In14.Cu" signal "GND6")
		(32 "In15.Cu" signal "IN6")
		(34 "In16.Cu" signal "GND7")
		(2 "B.Cu" signal "BOTTOM")
		(9 "F.Adhes" user "F.Adhesive")
		(11 "B.Adhes" user "B.Adhesive")
		(13 "F.Paste" user "Package Geometry/Pastemask Top")
		(15 "B.Paste" user "Package Geometry/Pastemask Bottom")
		(5 "F.SilkS" user "Ref Des/Silkscreen Top")
		(7 "B.SilkS" user "Ref Des/Silkscreen Bottom")
		(1 "F.Mask" user "Board Geometry/Soldermask Top")
		(3 "B.Mask" user "Board Geometry/Soldermask Bottom")
		(17 "Dwgs.User" user "User.Drawings")
		(19 "Cmts.User" user "User.Comments")
		(21 "Eco1.User" user "User.Eco1")
		(23 "Eco2.User" user "User.Eco2")
		(25 "Edge.Cuts" user "Board Geometry/Outline")
		(27 "Margin" user)
		(31 "F.CrtYd" user "Package Geometry/Place Bound Top")
		(29 "B.CrtYd" user "Package Geometry/Place Bound Bottom")
		(35 "F.Fab" user "Ref Des/Assembly Top")
		(33 "B.Fab" user "Ref Des/Assembly Bottom")
	)
	(footprint ""
		(layer "B.Cu")
		(at 189.865 -100.294948 90)
		(property "Reference" "R221"
			(at 0 0 90)
			(layer "B.SilkS")
			(hide yes)
			(effects
				(font
					(size 1.27 1.27)
				)
				(justify mirror)
			)
		)
		(property "Value" ""
			(at 0 0 90)
			(layer "B.Fab")
			(effects
				(font
					(size 1.27 1.27)
				)
				(justify mirror)
			)
		)
		(duplicate_pad_numbers_are_jumpers no)
		(fp_line
			(start 0.7874 -0.4064)
			(end -0.7874 -0.4064)
			(stroke
				(width 0.1524)
				(type default)
			)
			(layer "B.SilkS")
		)
		(fp_line
			(start -0.7874 -0.4064)
			(end -0.7874 0.4064)
			(stroke
				(width 0.1524)
				(type default)
			)
			(layer "B.SilkS")
		)
		(fp_line
			(start 0.7874 0.4064)
			(end 0.7874 -0.4064)
			(stroke
				(width 0.1524)
				(type default)
			)
			(layer "B.SilkS")
		)
		(fp_line
			(start -0.7874 0.4064)
			(end 0.7874 0.4064)
			(stroke
				(width 0.1524)
				(type default)
			)
			(layer "B.SilkS")
		)
		(fp_line
			(start 0.67945 -0.305054)
			(end 0.12065 -0.305054)
			(stroke
				(width 0.1)
				(type default)
			)
			(layer "B.Fab")
		)
		(fp_line
			(start 0.12065 -0.305054)
			(end 0.12065 -0.2794)
			(stroke
				(width 0.1)
				(type default)
			)
			(layer "B.Fab")
		)
		(fp_line
			(start -0.12065 -0.3048)
			(end -0.67945 -0.3048)
			(stroke
				(width 0.1)
				(type default)
			)
			(layer "B.Fab")
		)
		(fp_line
			(start -0.67945 -0.3048)
			(end -0.67945 0.3048)
			(stroke
				(width 0.1)
				(type default)
			)
			(layer "B.Fab")
		)
		(fp_line
			(start 0.12065 -0.2794)
			(end -0.12065 -0.2794)
			(stroke
				(width 0.1)
				(type default)
			)
			(layer "B.Fab")
		)
		(fp_line
			(start -0.12065 -0.2794)
			(end -0.12065 -0.3048)
			(stroke
				(width 0.1)
				(type default)
			)
			(layer "B.Fab")
		)
		(fp_line
			(start 0.12065 0.2794)
			(end 0.12065 0.3048)
			(stroke
				(width 0.1)
				(type default)
			)
			(layer "B.Fab")
		)
		(fp_line
			(start -0.120396 0.2794)
			(end 0.12065 0.2794)
			(stroke
				(width 0.1)
				(type default)
			)
			(layer "B.Fab")
		)
		(fp_line
			(start 0.67945 0.3048)
			(end 0.67945 -0.305054)
			(stroke
				(width 0.1)
				(type default)
			)
			(layer "B.Fab")
		)
		(fp_line
			(start 0.12065 0.3048)
			(end 0.67945 0.3048)
			(stroke
				(width 0.1)
				(type default)
			)
			(layer "B.Fab")
		)
		(fp_line
			(start -0.120396 0.3048)
			(end -0.120396 0.2794)
			(stroke
				(width 0.1)
				(type default)
			)
			(layer "B.Fab")
		)
		(fp_line
			(start -0.67945 0.3048)
			(end -0.120396 0.3048)
			(stroke
				(width 0.1)
				(type default)
			)
			(layer "B.Fab")
		)
		(pad "1" smd circle
			(at 0.40005 0 270)
			(size 0 0)
			(layers "B.Cu" "B.Mask" "B.Paste")
			(net "FM_CPU0_SA1")
		)
		(pad "2" smd circle
			(at -0.40005 0 270)
			(size 0 0)
			(layers "B.Cu" "B.Mask" "B.Paste")
			(net "CPU0_SA1")
		)
	)
	(footprint ""
		(layer "B.Cu")
		(at 136.459468 -41.028112 90)
		(property "Reference" "C6030"
			(at 0 0 90)
			(layer "B.SilkS")
			(hide yes)
			(effects
				(font
					(size 1.27 1.27)
				)
				(justify mirror)
			)
		)
		(property "Value" ""
			(at 0 0 90)
			(layer "B.Fab")
			(effects
				(font
					(size 1.27 1.27)
				)
				(justify mirror)
			)
		)
		(duplicate_pad_numbers_are_jumpers no)
		(fp_line
			(start 1.2954 -0.5842)
			(end -1.2954 -0.5842)
			(stroke
				(width 0.1524)
				(type default)
			)
			(layer "B.SilkS")
		)
		(fp_line
			(start -1.2954 -0.5842)
			(end -1.2954 0.5842)
			(stroke
				(width 0.1524)
				(type default)
			)
			(layer "B.SilkS")
		)
		(fp_line
			(start 1.2954 0.5842)
			(end 1.2954 -0.5842)
			(stroke
				(width 0.1524)
				(type default)
			)
			(layer "B.SilkS")
		)
		(fp_line
			(start -1.2954 0.5842)
			(end 1.2954 0.5842)
			(stroke
				(width 0.1524)
				(type default)
			)
			(layer "B.SilkS")
		)
		(fp_line
			(start 0.8636 -0.4572)
			(end -0.8636 -0.4572)
			(stroke
				(width 0.1)
				(type default)
			)
			(layer "B.Fab")
		)
		(fp_line
			(start -0.8636 -0.4572)
			(end -0.8636 -0.4064)
			(stroke
				(width 0.1)
				(type default)
			)
			(layer "B.Fab")
		)
		(fp_line
			(start 1.1938 -0.4064)
			(end 0.8636 -0.4064)
			(stroke
				(width 0.1)
				(type default)
			)
			(layer "B.Fab")
		)
		(fp_line
			(start 0.8636 -0.4064)
			(end 0.8636 -0.4572)
			(stroke
				(width 0.1)
				(type default)
			)
			(layer "B.Fab")
		)
		(fp_line
			(start -0.8636 -0.4064)
			(end -1.1938 -0.4064)
			(stroke
				(width 0.1)
				(type default)
			)
			(layer "B.Fab")
		)
		(fp_line
			(start -1.1938 -0.4064)
			(end -1.1938 0.4064)
			(stroke
				(width 0.1)
				(type default)
			)
			(layer "B.Fab")
		)
		(fp_line
			(start 1.1938 0.4064)
			(end 1.1938 -0.4064)
			(stroke
				(width 0.1)
				(type default)
			)
			(layer "B.Fab")
		)
		(fp_line
			(start 0.8636 0.4064)
			(end 1.1938 0.4064)
			(stroke
				(width 0.1)
				(type default)
			)
			(layer "B.Fab")
		)
		(fp_line
			(start -0.8636 0.4064)
			(end -0.8636 0.4572)
			(stroke
				(width 0.1)
				(type default)
			)
			(layer "B.Fab")
		)
		(fp_line
			(start -1.1938 0.4064)
			(end -0.8636 0.4064)
			(stroke
				(width 0.1)
				(type default)
			)
			(layer "B.Fab")
		)
		(fp_line
			(start 0.8636 0.4572)
			(end 0.8636 0.4064)
			(stroke
				(width 0.1)
				(type default)
			)
			(layer "B.Fab")
		)
		(fp_line
			(start -0.8636 0.4572)
			(end 0.8636 0.4572)
			(stroke
				(width 0.1)
				(type default)
			)
			(layer "B.Fab")
		)
		(pad "1" smd rect
			(at 0.7366 0)
			(size 0.7112 0.8128)
			(layers "B.Cu" "B.Mask" "B.Paste")
			(net "P1V2_CPU0_USB_DVDD12")
		)
		(pad "2" smd rect
			(at -0.7366 0)
			(size 0.7112 0.8128)
			(layers "B.Cu" "B.Mask" "B.Paste")
			(net "GND")
		)
	)
)
